(kicad_pcb
	(version 20260206)
	(generator "pcbnew")
	(generator_version "10.0")
	(general
		(thickness 1.6)
		(legacy_teardrops no)
	)
	(paper "A4")
	(title_block
		(title "01162023_DA0F0TEBIF0_F0T_Expander_BD_F_brd_V02_OCP.brd")
		(comment 1 "Grand Teton / footprints 7638-7645 of 9728")
	)
	(layers
		(0 "F.Cu" signal "TOP")
		(4 "In1.Cu" signal "GND")
		(6 "In2.Cu" signal "VCC")
		(8 "In3.Cu" signal "VCC1")
		(10 "In4.Cu" signal "GND1")
		(12 "In5.Cu" signal "IN1")
		(14 "In6.Cu" signal "GND2")
		(16 "In7.Cu" signal "IN2")
		(18 "In8.Cu" signal "GND3")
		(20 "In9.Cu" signal "IN3")
		(22 "In10.Cu" signal "GND4")
		(24 "In11.Cu" signal "IN4")
		(26 "In12.Cu" signal "GND5")
		(28 "In13.Cu" signal "IN5")
		(30 "In14.Cu" signal "GND6")
		(32 "In15.Cu" signal "IN6")
		(34 "In16.Cu" signal "GND7")
		(2 "B.Cu" signal "BOTTOM")
		(9 "F.Adhes" user "F.Adhesive")
		(11 "B.Adhes" user "B.Adhesive")
		(13 "F.Paste" user "Package Geometry/Pastemask Top")
		(15 "B.Paste" user "Package Geometry/Pastemask Bottom")
		(5 "F.SilkS" user "Ref Des/Silkscreen Top")
		(7 "B.SilkS" user "Ref Des/Silkscreen Bottom")
		(1 "F.Mask" user "Board Geometry/Soldermask Top")
		(3 "B.Mask" user "Board Geometry/Soldermask Bottom")
		(17 "Dwgs.User" user "User.Drawings")
		(19 "Cmts.User" user "User.Comments")
		(21 "Eco1.User" user "User.Eco1")
		(23 "Eco2.User" user "User.Eco2")
		(25 "Edge.Cuts" user "Board Geometry/Outline")
		(27 "Margin" user)
		(31 "F.CrtYd" user "Package Geometry/Place Bound Top")
		(29 "B.CrtYd" user "Package Geometry/Place Bound Bottom")
		(35 "F.Fab" user "Ref Des/Assembly Top")
		(33 "B.Fab" user "Ref Des/Assembly Bottom")
	)
	(footprint ""
		(layer "B.Cu")
		(at 293.797228 -109.481366)
		(property "Reference" "R286"
			(at 0 0 0)
			(layer "B.SilkS")
			(hide yes)
			(effects
				(font
					(size 1.27 1.27)
				)
				(justify mirror)
			)
		)
		(property "Value" ""
			(at 0 0 0)
			(layer "B.Fab")
			(effects
				(font
					(size 1.27 1.27)
				)
				(justify mirror)
			)
		)
		(duplicate_pad_numbers_are_jumpers no)
		(fp_line
			(start -0.7874 -0.4064)
			(end -0.7874 0.4064)
			(stroke
				(width 0.1524)
				(type default)
			)
			(layer "B.SilkS")
		)
		(fp_line
			(start -0.7874 0.4064)
			(end 0.7874 0.4064)
			(stroke
				(width 0.1524)
				(type default)
			)
			(layer "B.SilkS")
		)
		(fp_line
			(start 0.7874 -0.4064)
			(end -0.7874 -0.4064)
			(stroke
				(width 0.1524)
				(type default)
			)
			(layer "B.SilkS")
		)
		(fp_line
			(start 0.7874 0.4064)
			(end 0.7874 -0.4064)
			(stroke
				(width 0.1524)
				(type default)
			)
			(layer "B.SilkS")
		)
		(fp_line
			(start -0.67945 -0.3048)
			(end -0.67945 0.3048)
			(stroke
				(width 0.1)
				(type default)
			)
			(layer "B.Fab")
		)
		(fp_line
			(start -0.67945 0.3048)
			(end -0.120396 0.3048)
			(stroke
				(width 0.1)
				(type default)
			)
			(layer "B.Fab")
		)
		(fp_line
			(start -0.12065 -0.3048)
			(end -0.67945 -0.3048)
			(stroke
				(width 0.1)
				(type default)
			)
			(layer "B.Fab")
		)
		(fp_line
			(start -0.12065 -0.2794)
			(end -0.12065 -0.3048)
			(stroke
				(width 0.1)
				(type default)
			)
			(layer "B.Fab")
		)
		(fp_line
			(start -0.120396 0.2794)
			(end 0.12065 0.2794)
			(stroke
				(width 0.1)
				(type default)
			)
			(layer "B.Fab")
		)
		(fp_line
			(start -0.120396 0.3048)
			(end -0.120396 0.2794)
			(stroke
				(width 0.1)
				(type default)
			)
			(layer "B.Fab")
		)
		(fp_line
			(start 0.12065 -0.305054)
			(end 0.12065 -0.2794)
			(stroke
				(width 0.1)
				(type default)
			)
			(layer "B.Fab")
		)
		(fp_line
			(start 0.12065 -0.2794)
			(end -0.12065 -0.2794)
			(stroke
				(width 0.1)
				(type default)
			)
			(layer "B.Fab")
		)
		(fp_line
			(start 0.12065 0.2794)
			(end 0.12065 0.3048)
			(stroke
				(width 0.1)
				(type default)
			)
			(layer "B.Fab")
		)
		(fp_line
			(start 0.12065 0.3048)
			(end 0.67945 0.3048)
			(stroke
				(width 0.1)
				(type default)
			)
			(layer "B.Fab")
		)
		(fp_line
			(start 0.67945 -0.305054)
			(end 0.12065 -0.305054)
			(stroke
				(width 0.1)
				(type default)
			)
			(layer "B.Fab")
		)
		(fp_line
			(start 0.67945 0.3048)
			(end 0.67945 -0.305054)
			(stroke
				(width 0.1)
				(type default)
			)
			(layer "B.Fab")
		)
		(pad "1" smd circle
			(at 0.40005 0 180)
			(size 0 0)
			(layers "B.Cu" "B.Mask" "B.Paste")
			(net "NIC5_BIF1_N")
		)
		(pad "2" smd circle
			(at -0.40005 0 180)
			(size 0 0)
			(layers "B.Cu" "B.Mask" "B.Paste")
			(net "P3V3_AUX")
		)
	)
	(footprint ""
		(layer "B.Cu")
		(at 167.220392 -296.37482)
		(property "Reference" "C1370"
			(at 0 0 0)
			(layer "B.SilkS")
			(hide yes)
			(effects
				(font
					(size 1.27 1.27)
				)
				(justify mirror)
			)
		)
		(property "Value" ""
			(at 0 0 0)
			(layer "B.Fab")
			(effects
				(font
					(size 1.27 1.27)
				)
				(justify mirror)
			)
		)
		(duplicate_pad_numbers_are_jumpers no)
		(fp_line
			(start -0.299974 -0.150114)
			(end -0.299974 0.150114)
			(stroke
				(width 0.1)
				(type default)
			)
			(layer "B.Fab")
		)
		(fp_line
			(start -0.299974 0.150114)
			(end 0.299974 0.150114)
			(stroke
				(width 0.1)
				(type default)
			)
			(layer "B.Fab")
		)
		(fp_line
			(start 0.299974 -0.150114)
			(end -0.299974 -0.150114)
			(stroke
				(width 0.1)
				(type default)
			)
			(layer "B.Fab")
		)
		(fp_line
			(start 0.299974 0.150114)
			(end 0.299974 -0.150114)
			(stroke
				(width 0.1)
				(type default)
			)
			(layer "B.Fab")
		)
		(pad "1" smd rect
			(at 0.2667 0 180)
			(size 0.3048 0.381)
			(layers "B.Cu" "B.Mask" "B.Paste")
			(net "P0V8_PEX1")
		)
		(pad "2" smd rect
			(at -0.2667 0 180)
			(size 0.3048 0.381)
			(layers "B.Cu" "B.Mask" "B.Paste")
			(net "GND")
		)
	)
	(footprint ""
		(layer "B.Cu")
		(at 424.120818 -114.35207 90)
		(property "Reference" "C960"
			(at 0 0 90)
			(layer "B.SilkS")
			(hide yes)
			(effects
				(font
					(size 1.27 1.27)
				)
				(justify mirror)
			)
		)
		(property "Value" ""
			(at 0 0 90)
			(layer "B.Fab")
			(effects
				(font
					(size 1.27 1.27)
				)
				(justify mirror)
			)
		)
		(duplicate_pad_numbers_are_jumpers no)
		(fp_line
			(start 0.7874 -0.4064)
			(end -0.7874 -0.4064)
			(stroke
				(width 0.1524)
				(type default)
			)
			(layer "B.SilkS")
		)
		(fp_line
			(start -0.7874 -0.4064)
			(end -0.7874 0.4064)
			(stroke
				(width 0.1524)
				(type default)
			)
			(layer "B.SilkS")
		)
		(fp_line
			(start 0.7874 0.4064)
			(end 0.7874 -0.4064)
			(stroke
				(width 0.1524)
				(type default)
			)
			(layer "B.SilkS")
		)
		(fp_line
			(start -0.7874 0.4064)
			(end 0.7874 0.4064)
			(stroke
				(width 0.1524)
				(type default)
			)
			(layer "B.SilkS")
		)
		(fp_line
			(start 0.67945 -0.305054)
			(end 0.12065 -0.305054)
			(stroke
				(width 0.1)
				(type default)
			)
			(layer "B.Fab")
		)
		(fp_line
			(start 0.12065 -0.305054)
			(end 0.12065 -0.2794)
			(stroke
				(width 0.1)
				(type default)
			)
			(layer "B.Fab")
		)
		(fp_line
			(start -0.12065 -0.3048)
			(end -0.67945 -0.3048)
			(stroke
				(width 0.1)
				(type default)
			)
			(layer "B.Fab")
		)
		(fp_line
			(start -0.67945 -0.3048)
			(end -0.67945 0.3048)
			(stroke
				(width 0.1)
				(type default)
			)
			(layer "B.Fab")
		)
		(fp_line
			(start 0.12065 -0.2794)
			(end -0.12065 -0.2794)
			(stroke
				(width 0.1)
				(type default)
			)
			(layer "B.Fab")
		)
		(fp_line
			(start -0.12065 -0.2794)
			(end -0.12065 -0.3048)
			(stroke
				(width 0.1)
				(type default)
			)
			(layer "B.Fab")
		)
		(fp_line
			(start 0.12065 0.2794)
			(end 0.12065 0.3048)
			(stroke
				(width 0.1)
				(type default)
			)
			(layer "B.Fab")
		)
		(fp_line
			(start -0.120396 0.2794)
			(end 0.12065 0.2794)
			(stroke
				(width 0.1)
				(type default)
			)
			(layer "B.Fab")
		)
		(fp_line
			(start 0.67945 0.3048)
			(end 0.67945 -0.305054)
			(stroke
				(width 0.1)
				(type default)
			)
			(layer "B.Fab")
		)
		(fp_line
			(start 0.12065 0.3048)
			(end 0.67945 0.3048)
			(stroke
				(width 0.1)
				(type default)
			)
			(layer "B.Fab")
		)
		(fp_line
			(start -0.120396 0.3048)
			(end -0.120396 0.2794)
			(stroke
				(width 0.1)
				(type default)
			)
			(layer "B.Fab")
		)
		(fp_line
			(start -0.67945 0.3048)
			(end -0.120396 0.3048)
			(stroke
				(width 0.1)
				(type default)
			)
			(layer "B.Fab")
		)
		(pad "1" smd circle
			(at 0.40005 0 270)
			(size 0 0)
			(layers "B.Cu" "B.Mask" "B.Paste")
			(net "P3V3_NIC7")
		)
		(pad "2" smd circle
			(at -0.40005 0 270)
			(size 0 0)
			(layers "B.Cu" "B.Mask" "B.Paste")
			(net "GND")
		)
	)
	(footprint ""
		(layer "B.Cu")
		(at 115.466114 -256.226564 90)
		(property "Reference" "PR98"
			(at 0 0 90)
			(layer "B.SilkS")
			(hide yes)
			(effects
				(font
					(size 1.27 1.27)
				)
				(justify mirror)
			)
		)
		(property "Value" ""
			(at 0 0 90)
			(layer "B.Fab")
			(effects
				(font
					(size 1.27 1.27)
				)
				(justify mirror)
			)
		)
		(duplicate_pad_numbers_are_jumpers no)
		(fp_line
			(start 0.7874 -0.4064)
			(end -0.7874 -0.4064)
			(stroke
				(width 0.1524)
				(type default)
			)
			(layer "B.SilkS")
		)
		(fp_line
			(start -0.7874 -0.4064)
			(end -0.7874 0.4064)
			(stroke
				(width 0.1524)
				(type default)
			)
			(layer "B.SilkS")
		)
		(fp_line
			(start 0.7874 0.4064)
			(end 0.7874 -0.4064)
			(stroke
				(width 0.1524)
				(type default)
			)
			(layer "B.SilkS")
		)
		(fp_line
			(start -0.7874 0.4064)
			(end 0.7874 0.4064)
			(stroke
				(width 0.1524)
				(type default)
			)
			(layer "B.SilkS")
		)
		(fp_line
			(start 0.67945 -0.305054)
			(end 0.12065 -0.305054)
			(stroke
				(width 0.1)
				(type default)
			)
			(layer "B.Fab")
		)
		(fp_line
			(start 0.12065 -0.305054)
			(end 0.12065 -0.2794)
			(stroke
				(width 0.1)
				(type default)
			)
			(layer "B.Fab")
		)
		(fp_line
			(start -0.12065 -0.3048)
			(end -0.67945 -0.3048)
			(stroke
				(width 0.1)
				(type default)
			)
			(layer "B.Fab")
		)
		(fp_line
			(start -0.67945 -0.3048)
			(end -0.67945 0.3048)
			(stroke
				(width 0.1)
				(type default)
			)
			(layer "B.Fab")
		)
		(fp_line
			(start 0.12065 -0.2794)
			(end -0.12065 -0.2794)
			(stroke
				(width 0.1)
				(type default)
			)
			(layer "B.Fab")
		)
		(fp_line
			(start -0.12065 -0.2794)
			(end -0.12065 -0.3048)
			(stroke
				(width 0.1)
				(type default)
			)
			(layer "B.Fab")
		)
		(fp_line
			(start 0.12065 0.2794)
			(end 0.12065 0.3048)
			(stroke
				(width 0.1)
				(type default)
			)
			(layer "B.Fab")
		)
		(fp_line
			(start -0.120396 0.2794)
			(end 0.12065 0.2794)
			(stroke
				(width 0.1)
				(type default)
			)
			(layer "B.Fab")
		)
		(fp_line
			(start 0.67945 0.3048)
			(end 0.67945 -0.305054)
			(stroke
				(width 0.1)
				(type default)
			)
			(layer "B.Fab")
		)
		(fp_line
			(start 0.12065 0.3048)
			(end 0.67945 0.3048)
			(stroke
				(width 0.1)
				(type default)
			)
			(layer "B.Fab")
		)
		(fp_line
			(start -0.120396 0.3048)
			(end -0.120396 0.2794)
			(stroke
				(width 0.1)
				(type default)
			)
			(layer "B.Fab")
		)
		(fp_line
			(start -0.67945 0.3048)
			(end -0.120396 0.3048)
			(stroke
				(width 0.1)
				(type default)
			)
			(layer "B.Fab")
		)
		(pad "1" smd circle
			(at 0.40005 0 270)
			(size 0 0)
			(layers "B.Cu" "B.Mask" "B.Paste")
			(net "P0V8_PEX0_VINSEN")
		)
		(pad "2" smd circle
			(at -0.40005 0 270)
			(size 0 0)
			(layers "B.Cu" "B.Mask" "B.Paste")
			(net "GND")
		)
	)
	(footprint ""
		(layer "B.Cu")
		(at 379.349 -80.772)
		(property "Reference" "R6304"
			(at 0 0 0)
			(layer "B.SilkS")
			(hide yes)
			(effects
				(font
					(size 1.27 1.27)
				)
				(justify mirror)
			)
		)
		(property "Value" ""
			(at 0 0 0)
			(layer "B.Fab")
			(effects
				(font
					(size 1.27 1.27)
				)
				(justify mirror)
			)
		)
		(duplicate_pad_numbers_are_jumpers no)
		(fp_line
			(start -0.7874 -0.4064)
			(end -0.7874 0.4064)
			(stroke
				(width 0.1524)
				(type default)
			)
			(layer "B.SilkS")
		)
		(fp_line
			(start -0.7874 0.4064)
			(end 0.7874 0.4064)
			(stroke
				(width 0.1524)
				(type default)
			)
			(layer "B.SilkS")
		)
		(fp_line
			(start 0.7874 -0.4064)
			(end -0.7874 -0.4064)
			(stroke
				(width 0.1524)
				(type default)
			)
			(layer "B.SilkS")
		)
		(fp_line
			(start 0.7874 0.4064)
			(end 0.7874 -0.4064)
			(stroke
				(width 0.1524)
				(type default)
			)
			(layer "B.SilkS")
		)
		(fp_line
			(start -0.67945 -0.3048)
			(end -0.67945 0.3048)
			(stroke
				(width 0.1)
				(type default)
			)
			(layer "B.Fab")
		)
		(fp_line
			(start -0.67945 0.3048)
			(end -0.120396 0.3048)
			(stroke
				(width 0.1)
				(type default)
			)
			(layer "B.Fab")
		)
		(fp_line
			(start -0.12065 -0.3048)
			(end -0.67945 -0.3048)
			(stroke
				(width 0.1)
				(type default)
			)
			(layer "B.Fab")
		)
		(fp_line
			(start -0.12065 -0.2794)
			(end -0.12065 -0.3048)
			(stroke
				(width 0.1)
				(type default)
			)
			(layer "B.Fab")
		)
		(fp_line
			(start -0.120396 0.2794)
			(end 0.12065 0.2794)
			(stroke
				(width 0.1)
				(type default)
			)
			(layer "B.Fab")
		)
		(fp_line
			(start -0.120396 0.3048)
			(end -0.120396 0.2794)
			(stroke
				(width 0.1)
				(type default)
			)
			(layer "B.Fab")
		)
		(fp_line
			(start 0.12065 -0.305054)
			(end 0.12065 -0.2794)
			(stroke
				(width 0.1)
				(type default)
			)
			(layer "B.Fab")
		)
		(fp_line
			(start 0.12065 -0.2794)
			(end -0.12065 -0.2794)
			(stroke
				(width 0.1)
				(type default)
			)
			(layer "B.Fab")
		)
		(fp_line
			(start 0.12065 0.2794)
			(end 0.12065 0.3048)
			(stroke
				(width 0.1)
				(type default)
			)
			(layer "B.Fab")
		)
		(fp_line
			(start 0.12065 0.3048)
			(end 0.67945 0.3048)
			(stroke
				(width 0.1)
				(type default)
			)
			(layer "B.Fab")
		)
		(fp_line
			(start 0.67945 -0.305054)
			(end 0.12065 -0.305054)
			(stroke
				(width 0.1)
				(type default)
			)
			(layer "B.Fab")
		)
		(fp_line
			(start 0.67945 0.3048)
			(end 0.67945 -0.305054)
			(stroke
				(width 0.1)
				(type default)
			)
			(layer "B.Fab")
		)
		(pad "1" smd circle
			(at 0.40005 0 180)
			(size 0 0)
			(layers "B.Cu" "B.Mask" "B.Paste")
			(net "SMB_BIC_I2C6_MUX_THERMAL_R2_SCL")
		)
		(pad "2" smd circle
			(at -0.40005 0 180)
			(size 0 0)
			(layers "B.Cu" "B.Mask" "B.Paste")
			(net "SMB_BIC_I2C6_MUX_THERMAL_R_SCL")
		)
	)
	(footprint ""
		(layer "B.Cu")
		(at 422.326816 -301.124874 -90)
		(property "Reference" "R1447"
			(at 0 0 90)
			(layer "B.SilkS")
			(hide yes)
			(effects
				(font
					(size 1.27 1.27)
				)
				(justify mirror)
			)
		)
		(property "Value" ""
			(at 0 0 90)
			(layer "B.Fab")
			(effects
				(font
					(size 1.27 1.27)
				)
				(justify mirror)
			)
		)
		(duplicate_pad_numbers_are_jumpers no)
		(fp_line
			(start -0.7874 0.4064)
			(end 0.7874 0.4064)
			(stroke
				(width 0.1524)
				(type default)
			)
			(layer "B.SilkS")
		)
		(fp_line
			(start 0.7874 0.4064)
			(end 0.7874 -0.4064)
			(stroke
				(width 0.1524)
				(type default)
			)
			(layer "B.SilkS")
		)
		(fp_line
			(start -0.7874 -0.4064)
			(end -0.7874 0.4064)
			(stroke
				(width 0.1524)
				(type default)
			)
			(layer "B.SilkS")
		)
		(fp_line
			(start 0.7874 -0.4064)
			(end -0.7874 -0.4064)
			(stroke
				(width 0.1524)
				(type default)
			)
			(layer "B.SilkS")
		)
		(fp_line
			(start -0.67945 0.3048)
			(end -0.120396 0.3048)
			(stroke
				(width 0.1)
				(type default)
			)
			(layer "B.Fab")
		)
		(fp_line
			(start -0.120396 0.3048)
			(end -0.120396 0.2794)
			(stroke
				(width 0.1)
				(type default)
			)
			(layer "B.Fab")
		)
		(fp_line
			(start 0.12065 0.3048)
			(end 0.67945 0.3048)
			(stroke
				(width 0.1)
				(type default)
			)
			(layer "B.Fab")
		)
		(fp_line
			(start 0.67945 0.3048)
			(end 0.67945 -0.305054)
			(stroke
				(width 0.1)
				(type default)
			)
			(layer "B.Fab")
		)
		(fp_line
			(start -0.120396 0.2794)
			(end 0.12065 0.2794)
			(stroke
				(width 0.1)
				(type default)
			)
			(layer "B.Fab")
		)
		(fp_line
			(start 0.12065 0.2794)
			(end 0.12065 0.3048)
			(stroke
				(width 0.1)
				(type default)
			)
			(layer "B.Fab")
		)
		(fp_line
			(start -0.12065 -0.2794)
			(end -0.12065 -0.3048)
			(stroke
				(width 0.1)
				(type default)
			)
			(layer "B.Fab")
		)
		(fp_line
			(start 0.12065 -0.2794)
			(end -0.12065 -0.2794)
			(stroke
				(width 0.1)
				(type default)
			)
			(layer "B.Fab")
		)
		(fp_line
			(start -0.67945 -0.3048)
			(end -0.67945 0.3048)
			(stroke
				(width 0.1)
				(type default)
			)
			(layer "B.Fab")
		)
		(fp_line
			(start -0.12065 -0.3048)
			(end -0.67945 -0.3048)
			(stroke
				(width 0.1)
				(type default)
			)
			(layer "B.Fab")
		)
		(fp_line
			(start 0.12065 -0.305054)
			(end 0.12065 -0.2794)
			(stroke
				(width 0.1)
				(type default)
			)
			(layer "B.Fab")
		)
		(fp_line
			(start 0.67945 -0.305054)
			(end 0.12065 -0.305054)
			(stroke
				(width 0.1)
				(type default)
			)
			(layer "B.Fab")
		)
		(pad "1" smd circle
			(at 0.40005 0 90)
			(size 0 0)
			(layers "B.Cu" "B.Mask" "B.Paste")
			(net "PEX3_ADCTEMP_VINP0")
		)
		(pad "2" smd circle
			(at -0.40005 0 90)
			(size 0 0)
			(layers "B.Cu" "B.Mask" "B.Paste")
			(net "GND")
		)
	)
	(footprint ""
		(layer "B.Cu")
		(at 278.554942 -301.0408)
		(property "Reference" "C3347"
			(at 0 0 0)
			(layer "B.SilkS")
			(hide yes)
			(effects
				(font
					(size 1.27 1.27)
				)
				(justify mirror)
			)
		)
		(property "Value" ""
			(at 0 0 0)
			(layer "B.Fab")
			(effects
				(font
					(size 1.27 1.27)
				)
				(justify mirror)
			)
		)
		(duplicate_pad_numbers_are_jumpers no)
		(fp_line
			(start -0.299974 -0.150114)
			(end -0.299974 0.150114)
			(stroke
				(width 0.1)
				(type default)
			)
			(layer "B.Fab")
		)
		(fp_line
			(start -0.299974 0.150114)
			(end 0.299974 0.150114)
			(stroke
				(width 0.1)
				(type default)
			)
			(layer "B.Fab")
		)
		(fp_line
			(start 0.299974 -0.150114)
			(end -0.299974 -0.150114)
			(stroke
				(width 0.1)
				(type default)
			)
			(layer "B.Fab")
		)
		(fp_line
			(start 0.299974 0.150114)
			(end 0.299974 -0.150114)
			(stroke
				(width 0.1)
				(type default)
			)
			(layer "B.Fab")
		)
		(pad "1" smd rect
			(at 0.2667 0 180)
			(size 0.3048 0.381)
			(layers "B.Cu" "B.Mask" "B.Paste")
			(net "P1V8_PEX")
		)
		(pad "2" smd rect
			(at -0.2667 0 180)
			(size 0.3048 0.381)
			(layers "B.Cu" "B.Mask" "B.Paste")
			(net "GND")
		)
	)
	(footprint ""
		(layer "B.Cu")
		(at 460.169006 -289.791648 180)
		(property "Reference" "PC998"
			(at 0 0 0)
			(layer "B.SilkS")
			(hide yes)
			(effects
				(font
					(size 1.27 1.27)
				)
				(justify mirror)
			)
		)
		(property "Value" ""
			(at 0 0 0)
			(layer "B.Fab")
			(effects
				(font
					(size 1.27 1.27)
				)
				(justify mirror)
			)
		)
		(duplicate_pad_numbers_are_jumpers no)
		(fp_line
			(start 1.524 0.762)
			(end 1.524 -0.762)
			(stroke
				(width 0.1524)
				(type default)
			)
			(layer "B.SilkS")
		)
		(fp_line
			(start 1.524 -0.762)
			(end -1.524 -0.762)
			(stroke
				(width 0.1524)
				(type default)
			)
			(layer "B.SilkS")
		)
		(fp_line
			(start -1.524 0.762)
			(end 1.524 0.762)
			(stroke
				(width 0.1524)
				(type default)
			)
			(layer "B.SilkS")
		)
		(fp_line
			(start -1.524 -0.762)
			(end -1.524 0.762)
			(stroke
				(width 0.1524)
				(type default)
			)
			(layer "B.SilkS")
		)
		(fp_line
			(start 1.1049 0.724916)
			(end -1.1049 0.724916)
			(stroke
				(width 0.1)
				(type default)
			)
			(layer "B.Fab")
		)
		(fp_line
			(start 1.1049 -0.724916)
			(end 1.1049 0.724916)
			(stroke
				(width 0.1)
				(type default)
			)
			(layer "B.Fab")
		)
		(fp_line
			(start -1.1049 0.724916)
			(end -1.1049 -0.724916)
			(stroke
				(width 0.1)
				(type default)
			)
			(layer "B.Fab")
		)
		(fp_line
			(start -1.1049 -0.724916)
			(end 1.1049 -0.724916)
			(stroke
				(width 0.1)
				(type default)
			)
			(layer "B.Fab")
		)
		(pad "1" smd rect
			(at 0.889 0 180)
			(size 1.016 1.27)
			(layers "B.Cu" "B.Mask" "B.Paste")
			(net "P1V25_PEX3_R")
		)
		(pad "2" smd rect
			(at -0.889 0 180)
			(size 1.016 1.27)
			(layers "B.Cu" "B.Mask" "B.Paste")
			(net "GND")
		)
	)
)
